(kicad_pcb
	(version 20260206)
	(generator "pcbnew")
	(generator_version "10.0")
	(general
		(thickness 1.6)
		(legacy_teardrops no)
	)
	(paper "A4")
	(title_block
		(title "01162023_DA0F0TEBIF0_F0T_Expander_BD_F_brd_V02_OCP.brd")
		(comment 1 "Grand Teton / footprints 7261-7267 of 9728")
	)
	(layers
		(0 "F.Cu" signal "TOP")
		(4 "In1.Cu" signal "GND")
		(6 "In2.Cu" signal "VCC")
		(8 "In3.Cu" signal "VCC1")
		(10 "In4.Cu" signal "GND1")
		(12 "In5.Cu" signal "IN1")
		(14 "In6.Cu" signal "GND2")
		(16 "In7.Cu" signal "IN2")
		(18 "In8.Cu" signal "GND3")
		(20 "In9.Cu" signal "IN3")
		(22 "In10.Cu" signal "GND4")
		(24 "In11.Cu" signal "IN4")
		(26 "In12.Cu" signal "GND5")
		(28 "In13.Cu" signal "IN5")
		(30 "In14.Cu" signal "GND6")
		(32 "In15.Cu" signal "IN6")
		(34 "In16.Cu" signal "GND7")
		(2 "B.Cu" signal "BOTTOM")
		(9 "F.Adhes" user "F.Adhesive")
		(11 "B.Adhes" user "B.Adhesive")
		(13 "F.Paste" user "Package Geometry/Pastemask Top")
		(15 "B.Paste" user "Package Geometry/Pastemask Bottom")
		(5 "F.SilkS" user "Ref Des/Silkscreen Top")
		(7 "B.SilkS" user "Ref Des/Silkscreen Bottom")
		(1 "F.Mask" user "Board Geometry/Soldermask Top")
		(3 "B.Mask" user "Board Geometry/Soldermask Bottom")
		(17 "Dwgs.User" user "User.Drawings")
		(19 "Cmts.User" user "User.Comments")
		(21 "Eco1.User" user "User.Eco1")
		(23 "Eco2.User" user "User.Eco2")
		(25 "Edge.Cuts" user "Board Geometry/Outline")
		(27 "Margin" user)
		(31 "F.CrtYd" user "Package Geometry/Place Bound Top")
		(29 "B.CrtYd" user "Package Geometry/Place Bound Bottom")
		(35 "F.Fab" user "Ref Des/Assembly Top")
		(33 "B.Fab" user "Ref Des/Assembly Bottom")
	)
	(footprint ""
		(layer "B.Cu")
		(at 101.223318 -392.9888 180)
		(property "Reference" "C3631"
			(at 0 0 0)
			(layer "B.SilkS")
			(hide yes)
			(effects
				(font
					(size 1.27 1.27)
				)
				(justify mirror)
			)
		)
		(property "Value" ""
			(at 0 0 0)
			(layer "B.Fab")
			(effects
				(font
					(size 1.27 1.27)
				)
				(justify mirror)
			)
		)
		(duplicate_pad_numbers_are_jumpers no)
		(fp_line
			(start 0.7874 0.4064)
			(end 0.7874 -0.4064)
			(stroke
				(width 0.1524)
				(type default)
			)
			(layer "B.SilkS")
		)
		(fp_line
			(start 0.7874 -0.4064)
			(end -0.7874 -0.4064)
			(stroke
				(width 0.1524)
				(type default)
			)
			(layer "B.SilkS")
		)
		(fp_line
			(start -0.7874 0.4064)
			(end 0.7874 0.4064)
			(stroke
				(width 0.1524)
				(type default)
			)
			(layer "B.SilkS")
		)
		(fp_line
			(start -0.7874 -0.4064)
			(end -0.7874 0.4064)
			(stroke
				(width 0.1524)
				(type default)
			)
			(layer "B.SilkS")
		)
		(fp_line
			(start 0.67945 0.3048)
			(end 0.67945 -0.305054)
			(stroke
				(width 0.1)
				(type default)
			)
			(layer "B.Fab")
		)
		(fp_line
			(start 0.67945 -0.305054)
			(end 0.12065 -0.305054)
			(stroke
				(width 0.1)
				(type default)
			)
			(layer "B.Fab")
		)
		(fp_line
			(start 0.12065 0.3048)
			(end 0.67945 0.3048)
			(stroke
				(width 0.1)
				(type default)
			)
			(layer "B.Fab")
		)
		(fp_line
			(start 0.12065 0.2794)
			(end 0.12065 0.3048)
			(stroke
				(width 0.1)
				(type default)
			)
			(layer "B.Fab")
		)
		(fp_line
			(start 0.12065 -0.2794)
			(end -0.12065 -0.2794)
			(stroke
				(width 0.1)
				(type default)
			)
			(layer "B.Fab")
		)
		(fp_line
			(start 0.12065 -0.305054)
			(end 0.12065 -0.2794)
			(stroke
				(width 0.1)
				(type default)
			)
			(layer "B.Fab")
		)
		(fp_line
			(start -0.120396 0.3048)
			(end -0.120396 0.2794)
			(stroke
				(width 0.1)
				(type default)
			)
			(layer "B.Fab")
		)
		(fp_line
			(start -0.120396 0.2794)
			(end 0.12065 0.2794)
			(stroke
				(width 0.1)
				(type default)
			)
			(layer "B.Fab")
		)
		(fp_line
			(start -0.12065 -0.2794)
			(end -0.12065 -0.3048)
			(stroke
				(width 0.1)
				(type default)
			)
			(layer "B.Fab")
		)
		(fp_line
			(start -0.12065 -0.3048)
			(end -0.67945 -0.3048)
			(stroke
				(width 0.1)
				(type default)
			)
			(layer "B.Fab")
		)
		(fp_line
			(start -0.67945 0.3048)
			(end -0.120396 0.3048)
			(stroke
				(width 0.1)
				(type default)
			)
			(layer "B.Fab")
		)
		(fp_line
			(start -0.67945 -0.3048)
			(end -0.67945 0.3048)
			(stroke
				(width 0.1)
				(type default)
			)
			(layer "B.Fab")
		)
		(pad "1" smd circle
			(at 0.40005 0)
			(size 0 0)
			(layers "B.Cu" "B.Mask" "B.Paste")
			(net "P3V3_BIC_USB_HUB")
		)
		(pad "2" smd circle
			(at -0.40005 0)
			(size 0 0)
			(layers "B.Cu" "B.Mask" "B.Paste")
			(net "GND")
		)
	)
	(footprint ""
		(layer "B.Cu")
		(at 419.590728 -118.711218 180)
		(property "Reference" "R381"
			(at 0 0 0)
			(layer "B.SilkS")
			(hide yes)
			(effects
				(font
					(size 1.27 1.27)
				)
				(justify mirror)
			)
		)
		(property "Value" ""
			(at 0 0 0)
			(layer "B.Fab")
			(effects
				(font
					(size 1.27 1.27)
				)
				(justify mirror)
			)
		)
		(duplicate_pad_numbers_are_jumpers no)
		(fp_line
			(start 0.7874 0.4064)
			(end 0.7874 -0.4064)
			(stroke
				(width 0.1524)
				(type default)
			)
			(layer "B.SilkS")
		)
		(fp_line
			(start 0.7874 -0.4064)
			(end -0.7874 -0.4064)
			(stroke
				(width 0.1524)
				(type default)
			)
			(layer "B.SilkS")
		)
		(fp_line
			(start -0.7874 0.4064)
			(end 0.7874 0.4064)
			(stroke
				(width 0.1524)
				(type default)
			)
			(layer "B.SilkS")
		)
		(fp_line
			(start -0.7874 -0.4064)
			(end -0.7874 0.4064)
			(stroke
				(width 0.1524)
				(type default)
			)
			(layer "B.SilkS")
		)
		(fp_line
			(start 0.67945 0.3048)
			(end 0.67945 -0.305054)
			(stroke
				(width 0.1)
				(type default)
			)
			(layer "B.Fab")
		)
		(fp_line
			(start 0.67945 -0.305054)
			(end 0.12065 -0.305054)
			(stroke
				(width 0.1)
				(type default)
			)
			(layer "B.Fab")
		)
		(fp_line
			(start 0.12065 0.3048)
			(end 0.67945 0.3048)
			(stroke
				(width 0.1)
				(type default)
			)
			(layer "B.Fab")
		)
		(fp_line
			(start 0.12065 0.2794)
			(end 0.12065 0.3048)
			(stroke
				(width 0.1)
				(type default)
			)
			(layer "B.Fab")
		)
		(fp_line
			(start 0.12065 -0.2794)
			(end -0.12065 -0.2794)
			(stroke
				(width 0.1)
				(type default)
			)
			(layer "B.Fab")
		)
		(fp_line
			(start 0.12065 -0.305054)
			(end 0.12065 -0.2794)
			(stroke
				(width 0.1)
				(type default)
			)
			(layer "B.Fab")
		)
		(fp_line
			(start -0.120396 0.3048)
			(end -0.120396 0.2794)
			(stroke
				(width 0.1)
				(type default)
			)
			(layer "B.Fab")
		)
		(fp_line
			(start -0.120396 0.2794)
			(end 0.12065 0.2794)
			(stroke
				(width 0.1)
				(type default)
			)
			(layer "B.Fab")
		)
		(fp_line
			(start -0.12065 -0.2794)
			(end -0.12065 -0.3048)
			(stroke
				(width 0.1)
				(type default)
			)
			(layer "B.Fab")
		)
		(fp_line
			(start -0.12065 -0.3048)
			(end -0.67945 -0.3048)
			(stroke
				(width 0.1)
				(type default)
			)
			(layer "B.Fab")
		)
		(fp_line
			(start -0.67945 0.3048)
			(end -0.120396 0.3048)
			(stroke
				(width 0.1)
				(type default)
			)
			(layer "B.Fab")
		)
		(fp_line
			(start -0.67945 -0.3048)
			(end -0.67945 0.3048)
			(stroke
				(width 0.1)
				(type default)
			)
			(layer "B.Fab")
		)
		(pad "1" smd circle
			(at 0.40005 0)
			(size 0 0)
			(layers "B.Cu" "B.Mask" "B.Paste")
			(net "NIC7_AUX_PWR_EN")
		)
		(pad "2" smd circle
			(at -0.40005 0)
			(size 0 0)
			(layers "B.Cu" "B.Mask" "B.Paste")
			(net "GND")
		)
	)
	(footprint ""
		(layer "B.Cu")
		(at 425.841922 -102.088696 180)
		(property "Reference" "R374"
			(at 0 0 0)
			(layer "B.SilkS")
			(hide yes)
			(effects
				(font
					(size 1.27 1.27)
				)
				(justify mirror)
			)
		)
		(property "Value" ""
			(at 0 0 0)
			(layer "B.Fab")
			(effects
				(font
					(size 1.27 1.27)
				)
				(justify mirror)
			)
		)
		(duplicate_pad_numbers_are_jumpers no)
		(fp_line
			(start 0.7874 0.4064)
			(end 0.7874 -0.4064)
			(stroke
				(width 0.1524)
				(type default)
			)
			(layer "B.SilkS")
		)
		(fp_line
			(start 0.7874 -0.4064)
			(end -0.7874 -0.4064)
			(stroke
				(width 0.1524)
				(type default)
			)
			(layer "B.SilkS")
		)
		(fp_line
			(start -0.7874 0.4064)
			(end 0.7874 0.4064)
			(stroke
				(width 0.1524)
				(type default)
			)
			(layer "B.SilkS")
		)
		(fp_line
			(start -0.7874 -0.4064)
			(end -0.7874 0.4064)
			(stroke
				(width 0.1524)
				(type default)
			)
			(layer "B.SilkS")
		)
		(fp_line
			(start 0.67945 0.3048)
			(end 0.67945 -0.305054)
			(stroke
				(width 0.1)
				(type default)
			)
			(layer "B.Fab")
		)
		(fp_line
			(start 0.67945 -0.305054)
			(end 0.12065 -0.305054)
			(stroke
				(width 0.1)
				(type default)
			)
			(layer "B.Fab")
		)
		(fp_line
			(start 0.12065 0.3048)
			(end 0.67945 0.3048)
			(stroke
				(width 0.1)
				(type default)
			)
			(layer "B.Fab")
		)
		(fp_line
			(start 0.12065 0.2794)
			(end 0.12065 0.3048)
			(stroke
				(width 0.1)
				(type default)
			)
			(layer "B.Fab")
		)
		(fp_line
			(start 0.12065 -0.2794)
			(end -0.12065 -0.2794)
			(stroke
				(width 0.1)
				(type default)
			)
			(layer "B.Fab")
		)
		(fp_line
			(start 0.12065 -0.305054)
			(end 0.12065 -0.2794)
			(stroke
				(width 0.1)
				(type default)
			)
			(layer "B.Fab")
		)
		(fp_line
			(start -0.120396 0.3048)
			(end -0.120396 0.2794)
			(stroke
				(width 0.1)
				(type default)
			)
			(layer "B.Fab")
		)
		(fp_line
			(start -0.120396 0.2794)
			(end 0.12065 0.2794)
			(stroke
				(width 0.1)
				(type default)
			)
			(layer "B.Fab")
		)
		(fp_line
			(start -0.12065 -0.2794)
			(end -0.12065 -0.3048)
			(stroke
				(width 0.1)
				(type default)
			)
			(layer "B.Fab")
		)
		(fp_line
			(start -0.12065 -0.3048)
			(end -0.67945 -0.3048)
			(stroke
				(width 0.1)
				(type default)
			)
			(layer "B.Fab")
		)
		(fp_line
			(start -0.67945 0.3048)
			(end -0.120396 0.3048)
			(stroke
				(width 0.1)
				(type default)
			)
			(layer "B.Fab")
		)
		(fp_line
			(start -0.67945 -0.3048)
			(end -0.67945 0.3048)
			(stroke
				(width 0.1)
				(type default)
			)
			(layer "B.Fab")
		)
		(pad "1" smd circle
			(at 0.40005 0)
			(size 0 0)
			(layers "B.Cu" "B.Mask" "B.Paste")
			(net "NCSI_NIC7_RXD1")
		)
		(pad "2" smd circle
			(at -0.40005 0)
			(size 0 0)
			(layers "B.Cu" "B.Mask" "B.Paste")
			(net "GND")
		)
	)
	(footprint ""
		(layer "B.Cu")
		(at 110.86719 -335.481676 90)
		(property "Reference" "R1220"
			(at 0 0 90)
			(layer "B.SilkS")
			(hide yes)
			(effects
				(font
					(size 1.27 1.27)
				)
				(justify mirror)
			)
		)
		(property "Value" ""
			(at 0 0 90)
			(layer "B.Fab")
			(effects
				(font
					(size 1.27 1.27)
				)
				(justify mirror)
			)
		)
		(duplicate_pad_numbers_are_jumpers no)
		(fp_line
			(start 0.7874 -0.4064)
			(end -0.7874 -0.4064)
			(stroke
				(width 0.1524)
				(type default)
			)
			(layer "B.SilkS")
		)
		(fp_line
			(start -0.7874 -0.4064)
			(end -0.7874 0.4064)
			(stroke
				(width 0.1524)
				(type default)
			)
			(layer "B.SilkS")
		)
		(fp_line
			(start 0.7874 0.4064)
			(end 0.7874 -0.4064)
			(stroke
				(width 0.1524)
				(type default)
			)
			(layer "B.SilkS")
		)
		(fp_line
			(start -0.7874 0.4064)
			(end 0.7874 0.4064)
			(stroke
				(width 0.1524)
				(type default)
			)
			(layer "B.SilkS")
		)
		(fp_line
			(start 0.67945 -0.305054)
			(end 0.12065 -0.305054)
			(stroke
				(width 0.1)
				(type default)
			)
			(layer "B.Fab")
		)
		(fp_line
			(start 0.12065 -0.305054)
			(end 0.12065 -0.2794)
			(stroke
				(width 0.1)
				(type default)
			)
			(layer "B.Fab")
		)
		(fp_line
			(start -0.12065 -0.3048)
			(end -0.67945 -0.3048)
			(stroke
				(width 0.1)
				(type default)
			)
			(layer "B.Fab")
		)
		(fp_line
			(start -0.67945 -0.3048)
			(end -0.67945 0.3048)
			(stroke
				(width 0.1)
				(type default)
			)
			(layer "B.Fab")
		)
		(fp_line
			(start 0.12065 -0.2794)
			(end -0.12065 -0.2794)
			(stroke
				(width 0.1)
				(type default)
			)
			(layer "B.Fab")
		)
		(fp_line
			(start -0.12065 -0.2794)
			(end -0.12065 -0.3048)
			(stroke
				(width 0.1)
				(type default)
			)
			(layer "B.Fab")
		)
		(fp_line
			(start 0.12065 0.2794)
			(end 0.12065 0.3048)
			(stroke
				(width 0.1)
				(type default)
			)
			(layer "B.Fab")
		)
		(fp_line
			(start -0.120396 0.2794)
			(end 0.12065 0.2794)
			(stroke
				(width 0.1)
				(type default)
			)
			(layer "B.Fab")
		)
		(fp_line
			(start 0.67945 0.3048)
			(end 0.67945 -0.305054)
			(stroke
				(width 0.1)
				(type default)
			)
			(layer "B.Fab")
		)
		(fp_line
			(start 0.12065 0.3048)
			(end 0.67945 0.3048)
			(stroke
				(width 0.1)
				(type default)
			)
			(layer "B.Fab")
		)
		(fp_line
			(start -0.120396 0.3048)
			(end -0.120396 0.2794)
			(stroke
				(width 0.1)
				(type default)
			)
			(layer "B.Fab")
		)
		(fp_line
			(start -0.67945 0.3048)
			(end -0.120396 0.3048)
			(stroke
				(width 0.1)
				(type default)
			)
			(layer "B.Fab")
		)
		(pad "1" smd circle
			(at 0.40005 0 270)
			(size 0 0)
			(layers "B.Cu" "B.Mask" "B.Paste")
			(net "P3V3")
		)
		(pad "2" smd circle
			(at -0.40005 0 270)
			(size 0 0)
			(layers "B.Cu" "B.Mask" "B.Paste")
			(net "PU_9ZXL0451E_HBW")
		)
	)
	(footprint ""
		(layer "B.Cu")
		(at 66.299842 -303.499774 -90)
		(property "Reference" "C2905"
			(at 0 0 90)
			(layer "B.SilkS")
			(hide yes)
			(effects
				(font
					(size 1.27 1.27)
				)
				(justify mirror)
			)
		)
		(property "Value" ""
			(at 0 0 90)
			(layer "B.Fab")
			(effects
				(font
					(size 1.27 1.27)
				)
				(justify mirror)
			)
		)
		(duplicate_pad_numbers_are_jumpers no)
		(fp_line
			(start -0.299974 0.150114)
			(end 0.299974 0.150114)
			(stroke
				(width 0.1)
				(type default)
			)
			(layer "B.Fab")
		)
		(fp_line
			(start 0.299974 0.150114)
			(end 0.299974 -0.150114)
			(stroke
				(width 0.1)
				(type default)
			)
			(layer "B.Fab")
		)
		(fp_line
			(start -0.299974 -0.150114)
			(end -0.299974 0.150114)
			(stroke
				(width 0.1)
				(type default)
			)
			(layer "B.Fab")
		)
		(fp_line
			(start 0.299974 -0.150114)
			(end -0.299974 -0.150114)
			(stroke
				(width 0.1)
				(type default)
			)
			(layer "B.Fab")
		)
		(pad "1" smd rect
			(at 0.2667 0 90)
			(size 0.3048 0.381)
			(layers "B.Cu" "B.Mask" "B.Paste")
			(net "P1V25_PEX0")
		)
		(pad "2" smd rect
			(at -0.2667 0 90)
			(size 0.3048 0.381)
			(layers "B.Cu" "B.Mask" "B.Paste")
			(net "GND")
		)
	)
	(footprint ""
		(layer "B.Cu")
		(at 213.106 -192.405 90)
		(property "Reference" "R6313"
			(at 0 0 90)
			(layer "B.SilkS")
			(hide yes)
			(effects
				(font
					(size 1.27 1.27)
				)
				(justify mirror)
			)
		)
		(property "Value" ""
			(at 0 0 90)
			(layer "B.Fab")
			(effects
				(font
					(size 1.27 1.27)
				)
				(justify mirror)
			)
		)
		(duplicate_pad_numbers_are_jumpers no)
		(fp_line
			(start 0.7874 -0.4064)
			(end -0.7874 -0.4064)
			(stroke
				(width 0.1524)
				(type default)
			)
			(layer "B.SilkS")
		)
		(fp_line
			(start -0.7874 -0.4064)
			(end -0.7874 0.4064)
			(stroke
				(width 0.1524)
				(type default)
			)
			(layer "B.SilkS")
		)
		(fp_line
			(start 0.7874 0.4064)
			(end 0.7874 -0.4064)
			(stroke
				(width 0.1524)
				(type default)
			)
			(layer "B.SilkS")
		)
		(fp_line
			(start -0.7874 0.4064)
			(end 0.7874 0.4064)
			(stroke
				(width 0.1524)
				(type default)
			)
			(layer "B.SilkS")
		)
		(fp_line
			(start 0.67945 -0.305054)
			(end 0.12065 -0.305054)
			(stroke
				(width 0.1)
				(type default)
			)
			(layer "B.Fab")
		)
		(fp_line
			(start 0.12065 -0.305054)
			(end 0.12065 -0.2794)
			(stroke
				(width 0.1)
				(type default)
			)
			(layer "B.Fab")
		)
		(fp_line
			(start -0.12065 -0.3048)
			(end -0.67945 -0.3048)
			(stroke
				(width 0.1)
				(type default)
			)
			(layer "B.Fab")
		)
		(fp_line
			(start -0.67945 -0.3048)
			(end -0.67945 0.3048)
			(stroke
				(width 0.1)
				(type default)
			)
			(layer "B.Fab")
		)
		(fp_line
			(start 0.12065 -0.2794)
			(end -0.12065 -0.2794)
			(stroke
				(width 0.1)
				(type default)
			)
			(layer "B.Fab")
		)
		(fp_line
			(start -0.12065 -0.2794)
			(end -0.12065 -0.3048)
			(stroke
				(width 0.1)
				(type default)
			)
			(layer "B.Fab")
		)
		(fp_line
			(start 0.12065 0.2794)
			(end 0.12065 0.3048)
			(stroke
				(width 0.1)
				(type default)
			)
			(layer "B.Fab")
		)
		(fp_line
			(start -0.120396 0.2794)
			(end 0.12065 0.2794)
			(stroke
				(width 0.1)
				(type default)
			)
			(layer "B.Fab")
		)
		(fp_line
			(start 0.67945 0.3048)
			(end 0.67945 -0.305054)
			(stroke
				(width 0.1)
				(type default)
			)
			(layer "B.Fab")
		)
		(fp_line
			(start 0.12065 0.3048)
			(end 0.67945 0.3048)
			(stroke
				(width 0.1)
				(type default)
			)
			(layer "B.Fab")
		)
		(fp_line
			(start -0.120396 0.3048)
			(end -0.120396 0.2794)
			(stroke
				(width 0.1)
				(type default)
			)
			(layer "B.Fab")
		)
		(fp_line
			(start -0.67945 0.3048)
			(end -0.120396 0.3048)
			(stroke
				(width 0.1)
				(type default)
			)
			(layer "B.Fab")
		)
		(pad "1" smd circle
			(at 0.40005 0 270)
			(size 0 0)
			(layers "B.Cu" "B.Mask" "B.Paste")
			(net "SMB_NIC7_LS_SCL")
		)
		(pad "2" smd circle
			(at -0.40005 0 270)
			(size 0 0)
			(layers "B.Cu" "B.Mask" "B.Paste")
			(net "SMB_NIC7_LS_R_SCL")
		)
	)
	(footprint ""
		(layer "B.Cu")
		(at 232.125774 -92.936822 180)
		(property "Reference" "C2615"
			(at 0 0 0)
			(layer "B.SilkS")
			(hide yes)
			(effects
				(font
					(size 1.27 1.27)
				)
				(justify mirror)
			)
		)
		(property "Value" ""
			(at 0 0 0)
			(layer "B.Fab")
			(effects
				(font
					(size 1.27 1.27)
				)
				(justify mirror)
			)
		)
		(duplicate_pad_numbers_are_jumpers no)
		(fp_line
			(start 0.7874 0.4064)
			(end 0.7874 -0.4064)
			(stroke
				(width 0.1524)
				(type default)
			)
			(layer "B.SilkS")
		)
		(fp_line
			(start 0.7874 -0.4064)
			(end -0.7874 -0.4064)
			(stroke
				(width 0.1524)
				(type default)
			)
			(layer "B.SilkS")
		)
		(fp_line
			(start -0.7874 0.4064)
			(end 0.7874 0.4064)
			(stroke
				(width 0.1524)
				(type default)
			)
			(layer "B.SilkS")
		)
		(fp_line
			(start -0.7874 -0.4064)
			(end -0.7874 0.4064)
			(stroke
				(width 0.1524)
				(type default)
			)
			(layer "B.SilkS")
		)
		(fp_line
			(start 0.67945 0.3048)
			(end 0.67945 -0.305054)
			(stroke
				(width 0.1)
				(type default)
			)
			(layer "B.Fab")
		)
		(fp_line
			(start 0.67945 -0.305054)
			(end 0.12065 -0.305054)
			(stroke
				(width 0.1)
				(type default)
			)
			(layer "B.Fab")
		)
		(fp_line
			(start 0.12065 0.3048)
			(end 0.67945 0.3048)
			(stroke
				(width 0.1)
				(type default)
			)
			(layer "B.Fab")
		)
		(fp_line
			(start 0.12065 0.2794)
			(end 0.12065 0.3048)
			(stroke
				(width 0.1)
				(type default)
			)
			(layer "B.Fab")
		)
		(fp_line
			(start 0.12065 -0.2794)
			(end -0.12065 -0.2794)
			(stroke
				(width 0.1)
				(type default)
			)
			(layer "B.Fab")
		)
		(fp_line
			(start 0.12065 -0.305054)
			(end 0.12065 -0.2794)
			(stroke
				(width 0.1)
				(type default)
			)
			(layer "B.Fab")
		)
		(fp_line
			(start -0.120396 0.3048)
			(end -0.120396 0.2794)
			(stroke
				(width 0.1)
				(type default)
			)
			(layer "B.Fab")
		)
		(fp_line
			(start -0.120396 0.2794)
			(end 0.12065 0.2794)
			(stroke
				(width 0.1)
				(type default)
			)
			(layer "B.Fab")
		)
		(fp_line
			(start -0.12065 -0.2794)
			(end -0.12065 -0.3048)
			(stroke
				(width 0.1)
				(type default)
			)
			(layer "B.Fab")
		)
		(fp_line
			(start -0.12065 -0.3048)
			(end -0.67945 -0.3048)
			(stroke
				(width 0.1)
				(type default)
			)
			(layer "B.Fab")
		)
		(fp_line
			(start -0.67945 0.3048)
			(end -0.120396 0.3048)
			(stroke
				(width 0.1)
				(type default)
			)
			(layer "B.Fab")
		)
		(fp_line
			(start -0.67945 -0.3048)
			(end -0.67945 0.3048)
			(stroke
				(width 0.1)
				(type default)
			)
			(layer "B.Fab")
		)
		(pad "1" smd circle
			(at 0.40005 0)
			(size 0 0)
			(layers "B.Cu" "B.Mask" "B.Paste")
			(net "P3V3_PEX_USB_HUB")
		)
		(pad "2" smd circle
			(at -0.40005 0)
			(size 0 0)
			(layers "B.Cu" "B.Mask" "B.Paste")
			(net "GND")
		)
	)
)
